(kicad_pcb
	(version 20260206)
	(generator "pcbnew")
	(generator_version "10.0")
	(general
		(thickness 1.6)
		(legacy_teardrops no)
	)
	(paper "A4")
	(title_block
		(title "pdpb — Lightning_PDPB_BRD.brd")
		(comment 1 "Lightning (Wiwynn / Facebook NVMe JBOF) / footprints 492-492 of 1140")
	)
	(layers
		(0 "F.Cu" signal "TOP")
		(4 "In1.Cu" signal "L2GND")
		(6 "In2.Cu" signal "L3")
		(8 "In3.Cu" signal "L4VCC")
		(10 "In4.Cu" signal "L5VCC")
		(12 "In5.Cu" signal "L6")
		(14 "In6.Cu" signal "L7GND")
		(2 "B.Cu" signal "BOTTOM")
		(9 "F.Adhes" user "F.Adhesive")
		(11 "B.Adhes" user "B.Adhesive")
		(13 "F.Paste" user "Package Geometry/Pastemask Top")
		(15 "B.Paste" user "Package Geometry/Pastemask Bottom")
		(5 "F.SilkS" user "Ref Des/Silkscreen Top")
		(7 "B.SilkS" user "Ref Des/Silkscreen Bottom")
		(1 "F.Mask" user "Board Geometry/Soldermask Top")
		(3 "B.Mask" user "Board Geometry/Soldermask Bottom")
		(17 "Dwgs.User" user "User.Drawings")
		(19 "Cmts.User" user "User.Comments")
		(21 "Eco1.User" user "User.Eco1")
		(23 "Eco2.User" user "User.Eco2")
		(25 "Edge.Cuts" user "Board Geometry/Outline")
		(27 "Margin" user)
		(31 "F.CrtYd" user "Package Geometry/Place Bound Top")
		(29 "B.CrtYd" user "Package Geometry/Place Bound Bottom")
		(35 "F.Fab" user "Ref Des/Assembly Top")
		(33 "B.Fab" user "Ref Des/Assembly Bottom")
	)
	(footprint ""
		(layer "F.Cu")
		(at 20.850098 -129.329942 -90)
		(property "Reference" "J13"
			(at 0 0 270)
			(layer "F.SilkS")
			(hide yes)
			(effects
				(font
					(size 1.27 1.27)
				)
			)
		)
		(property "Value" "PCISLT68-14-GP-U1"
			(at -22.225 12.7508 270)
			(unlocked yes)
			(layer "F.Fab")
			(hide yes)
			(effects
				(font
					(size 1.016 1.016)
					(thickness 0.1524)
				)
			)
		)
		(property "Device Type" "SD-78827-0001"
			(at -22.225 11.2268 270)
			(unlocked yes)
			(layer "F.Fab")
			(hide yes)
			(effects
				(font
					(size 1.016 1.016)
					(thickness 0.1524)
				)
			)
		)
		(duplicate_pad_numbers_are_jumpers no)
		(fp_line
			(start -20.4724 12.0142)
			(end -20.4724 4.6736)
			(stroke
				(width 0.1524)
				(type default)
			)
			(layer "F.SilkS")
		)
		(fp_line
			(start -17.8435 12.0142)
			(end -20.4724 12.0142)
			(stroke
				(width 0.1524)
				(type default)
			)
			(layer "F.SilkS")
		)
		(fp_line
			(start 17.8435 12.0142)
			(end 17.8435 10.3124)
			(stroke
				(width 0.1524)
				(type default)
			)
			(layer "F.SilkS")
		)
		(fp_line
			(start 20.4724 12.0142)
			(end 17.8435 12.0142)
			(stroke
				(width 0.1524)
				(type default)
			)
			(layer "F.SilkS")
		)
		(fp_line
			(start -17.8435 10.3124)
			(end -17.8435 12.0142)
			(stroke
				(width 0.1524)
				(type default)
			)
			(layer "F.SilkS")
		)
		(fp_line
			(start 17.8435 10.3124)
			(end -17.8435 10.3124)
			(stroke
				(width 0.1524)
				(type default)
			)
			(layer "F.SilkS")
		)
		(fp_line
			(start -23.749 4.6736)
			(end -23.749 0.0254)
			(stroke
				(width 0.1524)
				(type default)
			)
			(layer "F.SilkS")
		)
		(fp_line
			(start -20.4724 4.6736)
			(end -23.749 4.6736)
			(stroke
				(width 0.1524)
				(type default)
			)
			(layer "F.SilkS")
		)
		(fp_line
			(start 20.4724 4.6736)
			(end 20.4724 12.0142)
			(stroke
				(width 0.1524)
				(type default)
			)
			(layer "F.SilkS")
		)
		(fp_line
			(start 23.749 4.6736)
			(end 20.4724 4.6736)
			(stroke
				(width 0.1524)
				(type default)
			)
			(layer "F.SilkS")
		)
		(fp_line
			(start -23.117556 2.896108)
			(end -23.117556 1.803908)
			(stroke
				(width 0.3048)
				(type default)
			)
			(layer "F.SilkS")
		)
		(fp_line
			(start 20.882356 2.896108)
			(end 20.882356 1.803908)
			(stroke
				(width 0.3048)
				(type default)
			)
			(layer "F.SilkS")
		)
		(fp_line
			(start -20.882356 1.803908)
			(end -20.882356 2.896108)
			(stroke
				(width 0.3048)
				(type default)
			)
			(layer "F.SilkS")
		)
		(fp_line
			(start 23.117556 1.803908)
			(end 23.117556 2.896108)
			(stroke
				(width 0.3048)
				(type default)
			)
			(layer "F.SilkS")
		)
		(fp_line
			(start -23.749 0.0254)
			(end -20.4724 0.0254)
			(stroke
				(width 0.1524)
				(type default)
			)
			(layer "F.SilkS")
		)
		(fp_line
			(start -20.4724 0.0254)
			(end -20.4724 -3.4036)
			(stroke
				(width 0.1524)
				(type default)
			)
			(layer "F.SilkS")
		)
		(fp_line
			(start 20.4724 0.0254)
			(end 23.749 0.0254)
			(stroke
				(width 0.1524)
				(type default)
			)
			(layer "F.SilkS")
		)
		(fp_line
			(start 23.749 0.0254)
			(end 23.749 4.6736)
			(stroke
				(width 0.1524)
				(type default)
			)
			(layer "F.SilkS")
		)
		(fp_line
			(start -20.4724 -3.4036)
			(end 20.4724 -3.4036)
			(stroke
				(width 0.1524)
				(type default)
			)
			(layer "F.SilkS")
		)
		(fp_line
			(start 20.4724 -3.4036)
			(end 20.4724 0.0254)
			(stroke
				(width 0.1524)
				(type default)
			)
			(layer "F.SilkS")
		)
		(fp_arc
			(start -20.882356 2.896108)
			(mid -21.999956 4.013708)
			(end -23.117556 2.896108)
			(stroke
				(width 0.3048)
				(type default)
			)
			(layer "F.SilkS")
		)
		(fp_arc
			(start 23.117556 2.896108)
			(mid 21.999956 4.013708)
			(end 20.882356 2.896108)
			(stroke
				(width 0.3048)
				(type default)
			)
			(layer "F.SilkS")
		)
		(fp_arc
			(start -23.117556 1.803908)
			(mid -21.999956 0.686308)
			(end -20.882356 1.803908)
			(stroke
				(width 0.3048)
				(type default)
			)
			(layer "F.SilkS")
		)
		(fp_arc
			(start 20.882356 1.803908)
			(mid 21.999956 0.686308)
			(end 23.117556 1.803908)
			(stroke
				(width 0.3048)
				(type default)
			)
			(layer "F.SilkS")
		)
		(fp_poly
			(pts
				(xy -20.2184 11.7602) (xy -20.2184 4.4196) (xy -23.495 4.4196) (xy -23.495 0.2794) (xy -20.2184 0.2794)
				(xy -20.2184 -3.1496) (xy 20.2184 -3.1496) (xy 20.2184 0.2794) (xy 23.495 0.2794) (xy 23.495 4.4196)
				(xy 20.2184 4.4196) (xy 20.2184 11.7602) (xy 18.0975 11.7602) (xy 18.0975 10.0584) (xy -18.0975 10.0584)
				(xy -18.0975 11.7602)
			)
			(stroke
				(width 0)
				(type default)
			)
			(fill no)
			(layer "F.CrtYd")
		)
		(fp_poly
			(pts
				(xy -21.2471 16.256) (xy -21.2471 4.9276) (xy -24.003 4.9276) (xy -24.003 -0.2286) (xy -20.7264 -0.2286)
				(xy -20.7264 -3.6576) (xy 20.7264 -3.6576) (xy 20.7264 -0.2286) (xy 24.003 -0.2286) (xy 24.003 -0.00635)
				(xy 20.2184 -0.00635) (xy 20.2184 -3.1496) (xy -20.2184 -3.1496) (xy -20.2184 0.2794) (xy -23.495 0.2794)
				(xy -23.495 4.4196) (xy -20.2184 4.4196) (xy -20.2184 11.7602) (xy -18.0975 11.7602) (xy -18.0975 10.0584)
				(xy 18.0975 10.0584) (xy 18.0975 11.7602) (xy 20.2184 11.7602) (xy 20.2184 4.4196) (xy 23.495 4.4196)
				(xy 23.495 0.2794) (xy 20.2184 0.2794) (xy 20.2184 0.00635) (xy 24.003 0.00635) (xy 24.003 4.9276)
				(xy 21.2471 4.9276) (xy 21.2471 16.256)
			)
			(stroke
				(width 0)
				(type default)
			)
			(fill no)
			(layer "F.CrtYd")
		)
		(fp_poly
			(pts
				(xy -21.2471 16.256) (xy -21.2471 4.9276) (xy -24.003 4.9276) (xy -24.003 -0.2286) (xy -20.7264 -0.2286)
				(xy -20.7264 -3.6576) (xy 20.7264 -3.6576) (xy 20.7264 -0.2286) (xy 24.003 -0.2286) (xy 24.003 4.9276)
				(xy 21.2471 4.9276) (xy 21.2471 16.256)
			)
			(stroke
				(width 0)
				(type default)
			)
			(fill no)
			(layer "F.Fab")
		)
		(pad "" np_thru_hole circle
			(at -18.999962 0 270)
			(size 0.254 0.254)
			(drill 1.8542)
			(layers "*.Cu" "*.Mask")
			(clearance 1.1557)
			(thermal_gap 1.1557)
		)
		(pad "" np_thru_hole circle
			(at 18.999962 0 270)
			(size 0.254 0.254)
			(drill 1.8542)
			(layers "*.Cu" "*.Mask")
			(clearance 1.1557)
			(thermal_gap 1.1557)
		)
		(pad "E1" smd rect
			(at -7.079996 1.240028 270)
			(size 0.508 2.0066)
			(layers "F.Cu" "F.Mask" "F.Paste")
			(net "PE_CLK100M_DR13_2_P")
		)
		(pad "E2" smd rect
			(at -6.279896 1.240028 270)
			(size 0.508 2.0066)
			(layers "F.Cu" "F.Mask" "F.Paste")
			(net "PE_CLK100M_DR13_2_N")
		)
		(pad "E3" smd rect
			(at -5.48005 1.240028 270)
			(size 0.508 2.0066)
			(layers "F.Cu" "F.Mask" "F.Paste")
			(net "P3V3")
		)
		(pad "E4" smd rect
			(at -4.67995 1.240028 270)
			(size 0.508 2.0066)
			(layers "F.Cu" "F.Mask" "F.Paste")
			(net "SSD13_PERST_N")
		)
		(pad "E5" smd rect
			(at -3.880104 1.240028 270)
			(size 0.508 2.0066)
			(layers "F.Cu" "F.Mask" "F.Paste")
			(net "SSD13_PERST_N")
		)
		(pad "E6" smd rect
			(at -3.080004 1.240028 270)
			(size 0.508 2.0066)
			(layers "F.Cu" "F.Mask" "F.Paste")
			(net "Net_1233")
		)
		(pad "E7" smd rect
			(at -15.48003 -1.949958 270)
			(size 0.508 2.0066)
			(layers "F.Cu" "F.Mask" "F.Paste")
			(net "PE_CLK100M_DR13_1_P")
		)
		(pad "E8" smd rect
			(at -14.67993 -1.949958 270)
			(size 0.508 2.0066)
			(layers "F.Cu" "F.Mask" "F.Paste")
			(net "PE_CLK100M_DR13_1_N")
		)
		(pad "E9" smd rect
			(at -13.880084 -1.949958 270)
			(size 0.508 2.0066)
			(layers "F.Cu" "F.Mask" "F.Paste")
			(net "GND")
		)
		(pad "E10" smd rect
			(at -13.079984 -1.949958 270)
			(size 0.508 2.0066)
			(layers "F.Cu" "F.Mask" "F.Paste")
			(net "PE_TX1_DR13_N")
		)
		(pad "E11" smd rect
			(at -12.279884 -1.949958 270)
			(size 0.508 2.0066)
			(layers "F.Cu" "F.Mask" "F.Paste")
			(net "PE_TX1_DR13_P")
		)
		(pad "E12" smd rect
			(at -11.480038 -1.949958 270)
			(size 0.508 2.0066)
			(layers "F.Cu" "F.Mask" "F.Paste")
			(net "GND")
		)
		(pad "E13" smd rect
			(at -10.679938 -1.949958 270)
			(size 0.508 2.0066)
			(layers "F.Cu" "F.Mask" "F.Paste")
			(net "PE_RX1_DR13_N")
		)
		(pad "E14" smd rect
			(at -9.880092 -1.949958 270)
			(size 0.508 2.0066)
			(layers "F.Cu" "F.Mask" "F.Paste")
			(net "PE_RX1_DR13_P")
		)
		(pad "E15" smd rect
			(at -9.079992 -1.949958 270)
			(size 0.508 2.0066)
			(layers "F.Cu" "F.Mask" "F.Paste")
			(net "GND")
		)
		(pad "E16" smd rect
			(at -8.279892 -1.949958 270)
			(size 0.508 2.0066)
			(layers "F.Cu" "F.Mask" "F.Paste")
			(net "Net_1240")
		)
		(pad "E17" smd rect
			(at 9.320022 -1.949958 270)
			(size 0.508 2.0066)
			(layers "F.Cu" "F.Mask" "F.Paste")
			(net "PE_TX4_DR13_N")
		)
		(pad "E18" smd rect
			(at 10.120122 -1.949958 270)
			(size 0.508 2.0066)
			(layers "F.Cu" "F.Mask" "F.Paste")
			(net "PE_TX4_DR13_P")
		)
		(pad "E19" smd rect
			(at 10.919968 -1.949958 270)
			(size 0.508 2.0066)
			(layers "F.Cu" "F.Mask" "F.Paste")
			(net "GND")
		)
		(pad "E20" smd rect
			(at 11.720068 -1.949958 270)
			(size 0.508 2.0066)
			(layers "F.Cu" "F.Mask" "F.Paste")
			(net "PE_RX4_DR13_N")
		)
		(pad "E21" smd rect
			(at 12.519914 -1.949958 270)
			(size 0.508 2.0066)
			(layers "F.Cu" "F.Mask" "F.Paste")
			(net "PE_RX4_DR13_P")
		)
		(pad "E22" smd rect
			(at 13.320014 -1.949958 270)
			(size 0.508 2.0066)
			(layers "F.Cu" "F.Mask" "F.Paste")
			(net "GND")
		)
		(pad "E23" smd rect
			(at 14.120114 -1.949958 270)
			(size 0.508 2.0066)
			(layers "F.Cu" "F.Mask" "F.Paste")
			(net "SCL_DR13_R")
		)
		(pad "E24" smd rect
			(at 14.91996 -1.949958 270)
			(size 0.508 2.0066)
			(layers "F.Cu" "F.Mask" "F.Paste")
			(net "SDA_DR13_R")
		)
		(pad "E25" smd rect
			(at 15.72006 -1.949958 270)
			(size 0.508 2.0066)
			(layers "F.Cu" "F.Mask" "F.Paste")
			(net "DUALPORTEN#13")
		)
		(pad "P1" smd rect
			(at -1.905 0.824992 270)
			(size 0.6604 2.0574)
			(layers "F.Cu" "F.Mask" "F.Paste")
			(net "Net_1236")
		)
		(pad "P2" smd rect
			(at -0.635 0.824992 270)
			(size 0.6604 2.0574)
			(layers "F.Cu" "F.Mask" "F.Paste")
			(net "Net_1235")
		)
		(pad "P3" smd rect
			(at 0.635 0.824992 270)
			(size 0.6604 2.0574)
			(layers "F.Cu" "F.Mask" "F.Paste")
			(net "Net_1234")
		)
		(pad "P4" smd rect
			(at 1.905 0.824992 270)
			(size 0.6604 2.0574)
			(layers "F.Cu" "F.Mask" "F.Paste")
			(net "SSD13_CLK0_OE_N")
		)
		(pad "P5" smd rect
			(at 3.175 0.824992 270)
			(size 0.6604 2.0574)
			(layers "F.Cu" "F.Mask" "F.Paste")
			(net "GND")
		)
		(pad "P6" smd rect
			(at 4.445 0.824992 270)
			(size 0.6604 2.0574)
			(layers "F.Cu" "F.Mask" "F.Paste")
			(net "GND")
		)
		(pad "P7" smd rect
			(at 5.715 0.824992 270)
			(size 0.6604 2.0574)
			(layers "F.Cu" "F.Mask" "F.Paste")
			(net "Net_102")
		)
		(pad "P8" smd rect
			(at 6.985 0.824992 270)
			(size 0.6604 2.0574)
			(layers "F.Cu" "F.Mask" "F.Paste")
			(net "Net_74")
		)
		(pad "P9" smd rect
			(at 8.255 0.824992 270)
			(size 0.6604 2.0574)
			(layers "F.Cu" "F.Mask" "F.Paste")
			(net "Net_88")
		)
		(pad "P10" smd rect
			(at 9.525 0.824992 270)
			(size 0.6604 2.0574)
			(layers "F.Cu" "F.Mask" "F.Paste")
			(net "SSD_PRSNT_NET13")
		)
		(pad "P11" smd rect
			(at 10.795 0.824992 270)
			(size 0.6604 2.0574)
			(layers "F.Cu" "F.Mask" "F.Paste")
			(net "SSD_ACT_DR13")
		)
		(pad "P12" smd rect
			(at 12.065 0.824992 270)
			(size 0.6604 2.0574)
			(layers "F.Cu" "F.Mask" "F.Paste")
			(net "GND")
		)
		(pad "P13" smd rect
			(at 13.335 0.824992 270)
			(size 0.6604 2.0574)
			(layers "F.Cu" "F.Mask" "F.Paste")
			(net "12V_PRECH_SSD13")
		)
		(pad "P14" smd rect
			(at 14.605 0.824992 270)
			(size 0.6604 2.0574)
			(layers "F.Cu" "F.Mask" "F.Paste")
			(net "P12V_SSD13")
		)
		(pad "P15" smd rect
			(at 15.875 0.824992 270)
			(size 0.6604 2.0574)
			(layers "F.Cu" "F.Mask" "F.Paste")
			(net "P12V_SSD13")
		)
		(pad "PTH1" thru_hole oval
			(at -21.999956 2.350008 270)
			(size 1.524 2.6162)
			(drill oval 0.8128 1.905)
			(layers "*.Cu" "*.Mask")
			(remove_unused_layers no)
			(net "Net_1245")
			(clearance 0.1524)
			(thermal_gap 0.1524)
		)
		(pad "PTH2" thru_hole oval
			(at 21.999956 2.350008 270)
			(size 1.524 2.6162)
			(drill oval 0.8128 1.905)
			(layers "*.Cu" "*.Mask")
			(remove_unused_layers no)
			(net "Net_1229")
			(clearance 0.1524)
			(thermal_gap 0.1524)
		)
		(pad "S1" smd rect
			(at -15.875 0.824992 270)
			(size 0.6604 2.0574)
			(layers "F.Cu" "F.Mask" "F.Paste")
			(net "GND")
		)
		(pad "S2" smd rect
			(at -14.605 0.824992 270)
			(size 0.6604 2.0574)
			(layers "F.Cu" "F.Mask" "F.Paste")
			(net "Net_1244")
		)
		(pad "S3" smd rect
			(at -13.335 0.824992 270)
			(size 0.6604 2.0574)
			(layers "F.Cu" "F.Mask" "F.Paste")
			(net "Net_1243")
		)
		(pad "S4" smd rect
			(at -12.065 0.824992 270)
			(size 0.6604 2.0574)
			(layers "F.Cu" "F.Mask" "F.Paste")
			(net "GND")
		)
		(pad "S5" smd rect
			(at -10.795 0.824992 270)
			(size 0.6604 2.0574)
			(layers "F.Cu" "F.Mask" "F.Paste")
			(net "Net_1242")
		)
		(pad "S6" smd rect
			(at -9.525 0.824992 270)
			(size 0.6604 2.0574)
			(layers "F.Cu" "F.Mask" "F.Paste")
			(net "Net_1241")
		)
		(pad "S7" smd rect
			(at -8.255 0.824992 270)
			(size 0.6604 2.0574)
			(layers "F.Cu" "F.Mask" "F.Paste")
			(net "GND")
		)
		(pad "S8" smd rect
			(at -7.480046 -1.949958 270)
			(size 0.508 2.0066)
			(layers "F.Cu" "F.Mask" "F.Paste")
			(net "GND")
		)
		(pad "S9" smd rect
			(at -6.679946 -1.949958 270)
			(size 0.508 2.0066)
			(layers "F.Cu" "F.Mask" "F.Paste")
			(net "Net_1239")
		)
		(pad "S10" smd rect
			(at -5.8801 -1.949958 270)
			(size 0.508 2.0066)
			(layers "F.Cu" "F.Mask" "F.Paste")
			(net "Net_1238")
		)
		(pad "S11" smd rect
			(at -5.08 -1.949958 270)
			(size 0.508 2.0066)
			(layers "F.Cu" "F.Mask" "F.Paste")
			(net "GND")
		)
		(pad "S12" smd rect
			(at -4.2799 -1.949958 270)
			(size 0.508 2.0066)
			(layers "F.Cu" "F.Mask" "F.Paste")
			(net "Net_1237")
		)
		(pad "S13" smd rect
			(at -3.480054 -1.949958 270)
			(size 0.508 2.0066)
			(layers "F.Cu" "F.Mask" "F.Paste")
			(net "Net_1232")
		)
		(pad "S14" smd rect
			(at -2.679954 -1.949958 270)
			(size 0.508 2.0066)
			(layers "F.Cu" "F.Mask" "F.Paste")
			(net "GND")
		)
		(pad "S15" smd rect
			(at -1.880108 -1.949958 270)
			(size 0.508 2.0066)
			(layers "F.Cu" "F.Mask" "F.Paste")
			(net "Net_1231")
		)
		(pad "S16" smd rect
			(at -1.080008 -1.949958 270)
			(size 0.508 2.0066)
			(layers "F.Cu" "F.Mask" "F.Paste")
			(net "GND")
		)
		(pad "S17" smd rect
			(at -0.279908 -1.949958 270)
			(size 0.508 2.0066)
			(layers "F.Cu" "F.Mask" "F.Paste")
			(net "PE_TX2_DR13_N")
		)
		(pad "S18" smd rect
			(at 0.519938 -1.949958 270)
			(size 0.508 2.0066)
			(layers "F.Cu" "F.Mask" "F.Paste")
			(net "PE_TX2_DR13_P")
		)
		(pad "S19" smd rect
			(at 1.320038 -1.949958 270)
			(size 0.508 2.0066)
			(layers "F.Cu" "F.Mask" "F.Paste")
			(net "GND")
		)
		(pad "S20" smd rect
			(at 2.119884 -1.949958 270)
			(size 0.508 2.0066)
			(layers "F.Cu" "F.Mask" "F.Paste")
			(net "PE_RX2_DR13_N")
		)
		(pad "S21" smd rect
			(at 2.919984 -1.949958 270)
			(size 0.508 2.0066)
			(layers "F.Cu" "F.Mask" "F.Paste")
			(net "PE_RX2_DR13_P")
		)
		(pad "S22" smd rect
			(at 3.720084 -1.949958 270)
			(size 0.508 2.0066)
			(layers "F.Cu" "F.Mask" "F.Paste")
			(net "GND")
		)
		(pad "S23" smd rect
			(at 4.51993 -1.949958 270)
			(size 0.508 2.0066)
			(layers "F.Cu" "F.Mask" "F.Paste")
			(net "PE_TX3_DR13_N")
		)
		(pad "S24" smd rect
			(at 5.32003 -1.949958 270)
			(size 0.508 2.0066)
			(layers "F.Cu" "F.Mask" "F.Paste")
			(net "PE_TX3_DR13_P")
		)
		(pad "S25" smd rect
			(at 6.119876 -1.949958 270)
			(size 0.508 2.0066)
			(layers "F.Cu" "F.Mask" "F.Paste")
			(net "GND")
		)
		(pad "S26" smd rect
			(at 6.919976 -1.949958 270)
			(size 0.508 2.0066)
			(layers "F.Cu" "F.Mask" "F.Paste")
			(net "PE_RX3_DR13_N")
		)
		(pad "S27" smd rect
			(at 7.720076 -1.949958 270)
			(size 0.508 2.0066)
			(layers "F.Cu" "F.Mask" "F.Paste")
			(net "PE_RX3_DR13_P")
		)
		(pad "S28" smd rect
			(at 8.519922 -1.949958 270)
			(size 0.508 2.0066)
			(layers "F.Cu" "F.Mask" "F.Paste")
			(net "GND")
		)
		(zone
			(layers "F.Cu" "B.Cu" "In1.Cu" "In2.Cu" "In3.Cu" "In4.Cu" "In5.Cu" "In6.Cu")
			(hatch none 0.5)
			(connect_pads
				(clearance 0)
			)
			(min_thickness 0.25)
			(keepout
				(tracks not_allowed)
				(vias allowed)
				(pads allowed)
				(copperpour not_allowed)
				(footprints allowed)
			)
			(placement
				(enabled no)
				(sheetname "")
			)
			(fill
				(thermal_gap 0.5)
				(thermal_bridge_width 0.5)
				(island_removal_mode 0)
			)
			(polygon
				(pts
					(arc
						(start 22.081998 -148.329904)
						(mid 19.618198 -148.329904)
						(end 22.081998 -148.329904)
					)
				)
			)
		)
		(zone
			(layers "F.Cu" "B.Cu" "In1.Cu" "In2.Cu" "In3.Cu" "In4.Cu" "In5.Cu" "In6.Cu")
			(hatch none 0.5)
			(connect_pads
				(clearance 0)
			)
			(min_thickness 0.25)
			(keepout
				(tracks not_allowed)
				(vias allowed)
				(pads allowed)
				(copperpour not_allowed)
				(footprints allowed)
			)
			(placement
				(enabled no)
				(sheetname "")
			)
			(fill
				(thermal_gap 0.5)
				(thermal_bridge_width 0.5)
				(island_removal_mode 0)
			)
			(polygon
				(pts
					(arc
						(start 22.081998 -110.32998)
						(mid 19.618198 -110.32998)
						(end 22.081998 -110.32998)
					)
				)
			)
		)
	)
)
